(kicad_pcb
	(version 20260206)
	(generator "pcbnew")
	(generator_version "10.0")
	(general
		(thickness 1.6)
		(legacy_teardrops no)
	)
	(paper "A4")
	(title_block
		(title "04192023_DAF0TMB3IC0_F0TG_MB_C_brd_V02_OCP.brd")
		(comment 1 "Grand Teton / footprints 1637-1643 of 8354")
	)
	(layers
		(0 "F.Cu" signal "TOP")
		(4 "In1.Cu" signal "GND")
		(6 "In2.Cu" signal "IN1")
		(8 "In3.Cu" signal "GND1")
		(10 "In4.Cu" signal "IN2")
		(12 "In5.Cu" signal "GND2")
		(14 "In6.Cu" signal "IN3")
		(16 "In7.Cu" signal "GND3")
		(18 "In8.Cu" signal "VCC")
		(20 "In9.Cu" signal "VCC1")
		(22 "In10.Cu" signal "GND4")
		(24 "In11.Cu" signal "IN4")
		(26 "In12.Cu" signal "GND5")
		(28 "In13.Cu" signal "IN5")
		(30 "In14.Cu" signal "GND6")
		(32 "In15.Cu" signal "IN6")
		(34 "In16.Cu" signal "GND7")
		(2 "B.Cu" signal "BOTTOM")
		(9 "F.Adhes" user "F.Adhesive")
		(11 "B.Adhes" user "B.Adhesive")
		(13 "F.Paste" user "Package Geometry/Pastemask Top")
		(15 "B.Paste" user "Package Geometry/Pastemask Bottom")
		(5 "F.SilkS" user "Ref Des/Silkscreen Top")
		(7 "B.SilkS" user "Ref Des/Silkscreen Bottom")
		(1 "F.Mask" user "Board Geometry/Soldermask Top")
		(3 "B.Mask" user "Board Geometry/Soldermask Bottom")
		(17 "Dwgs.User" user "User.Drawings")
		(19 "Cmts.User" user "User.Comments")
		(21 "Eco1.User" user "User.Eco1")
		(23 "Eco2.User" user "User.Eco2")
		(25 "Edge.Cuts" user "Board Geometry/Outline")
		(27 "Margin" user)
		(31 "F.CrtYd" user "Package Geometry/Place Bound Top")
		(29 "B.CrtYd" user "Package Geometry/Place Bound Bottom")
		(35 "F.Fab" user "Ref Des/Assembly Top")
		(33 "B.Fab" user "Ref Des/Assembly Bottom")
	)
	(footprint ""
		(layer "F.Cu")
		(at 62.861698 -26.99004 90)
		(property "Reference" "PR3853"
			(at 0 0 90)
			(layer "F.SilkS")
			(hide yes)
			(effects
				(font
					(size 1.27 1.27)
				)
			)
		)
		(property "Value" ""
			(at 0 0 90)
			(layer "F.Fab")
			(effects
				(font
					(size 1.27 1.27)
				)
			)
		)
		(duplicate_pad_numbers_are_jumpers no)
		(fp_line
			(start 0.7874 -0.4064)
			(end 0.7874 0.4064)
			(stroke
				(width 0.1524)
				(type default)
			)
			(layer "F.SilkS")
		)
		(fp_line
			(start -0.7874 -0.4064)
			(end 0.7874 -0.4064)
			(stroke
				(width 0.1524)
				(type default)
			)
			(layer "F.SilkS")
		)
		(fp_line
			(start 0.7874 0.4064)
			(end -0.7874 0.4064)
			(stroke
				(width 0.1524)
				(type default)
			)
			(layer "F.SilkS")
		)
		(fp_line
			(start -0.7874 0.4064)
			(end -0.7874 -0.4064)
			(stroke
				(width 0.1524)
				(type default)
			)
			(layer "F.SilkS")
		)
		(fp_line
			(start -0.12065 -0.305054)
			(end -0.12065 -0.2794)
			(stroke
				(width 0.1)
				(type default)
			)
			(layer "F.Fab")
		)
		(fp_line
			(start -0.67945 -0.305054)
			(end -0.12065 -0.305054)
			(stroke
				(width 0.1)
				(type default)
			)
			(layer "F.Fab")
		)
		(fp_line
			(start 0.67945 -0.3048)
			(end 0.67945 0.3048)
			(stroke
				(width 0.1)
				(type default)
			)
			(layer "F.Fab")
		)
		(fp_line
			(start 0.12065 -0.3048)
			(end 0.67945 -0.3048)
			(stroke
				(width 0.1)
				(type default)
			)
			(layer "F.Fab")
		)
		(fp_line
			(start 0.12065 -0.2794)
			(end 0.12065 -0.3048)
			(stroke
				(width 0.1)
				(type default)
			)
			(layer "F.Fab")
		)
		(fp_line
			(start -0.12065 -0.2794)
			(end 0.12065 -0.2794)
			(stroke
				(width 0.1)
				(type default)
			)
			(layer "F.Fab")
		)
		(fp_line
			(start 0.120396 0.2794)
			(end -0.12065 0.2794)
			(stroke
				(width 0.1)
				(type default)
			)
			(layer "F.Fab")
		)
		(fp_line
			(start -0.12065 0.2794)
			(end -0.12065 0.3048)
			(stroke
				(width 0.1)
				(type default)
			)
			(layer "F.Fab")
		)
		(fp_line
			(start 0.67945 0.3048)
			(end 0.120396 0.3048)
			(stroke
				(width 0.1)
				(type default)
			)
			(layer "F.Fab")
		)
		(fp_line
			(start 0.120396 0.3048)
			(end 0.120396 0.2794)
			(stroke
				(width 0.1)
				(type default)
			)
			(layer "F.Fab")
		)
		(fp_line
			(start -0.12065 0.3048)
			(end -0.67945 0.3048)
			(stroke
				(width 0.1)
				(type default)
			)
			(layer "F.Fab")
		)
		(fp_line
			(start -0.67945 0.3048)
			(end -0.67945 -0.305054)
			(stroke
				(width 0.1)
				(type default)
			)
			(layer "F.Fab")
		)
		(pad "1" smd circle
			(at -0.40005 0 90)
			(size 0 0)
			(layers "F.Cu" "F.Mask" "F.Paste")
			(net "P12V_AUX")
		)
		(pad "2" smd circle
			(at 0.40005 0 90)
			(size 0 0)
			(layers "F.Cu" "F.Mask" "F.Paste")
			(net "P12V_OCP_OV_FB_2")
		)
	)
	(footprint ""
		(layer "F.Cu")
		(at 76.07173 -388.030974 90)
		(property "Reference" "R626"
			(at 0 0 90)
			(layer "F.SilkS")
			(hide yes)
			(effects
				(font
					(size 1.27 1.27)
				)
			)
		)
		(property "Value" ""
			(at 0 0 90)
			(layer "F.Fab")
			(effects
				(font
					(size 1.27 1.27)
				)
			)
		)
		(duplicate_pad_numbers_are_jumpers no)
		(fp_line
			(start 0.32512 -0.175006)
			(end 0.32512 0.175006)
			(stroke
				(width 0.1)
				(type default)
			)
			(layer "F.Fab")
		)
		(fp_line
			(start -0.32512 -0.175006)
			(end 0.32512 -0.175006)
			(stroke
				(width 0.1)
				(type default)
			)
			(layer "F.Fab")
		)
		(fp_line
			(start 0.32512 0.175006)
			(end -0.32512 0.175006)
			(stroke
				(width 0.1)
				(type default)
			)
			(layer "F.Fab")
		)
		(fp_line
			(start -0.32512 0.175006)
			(end -0.32512 -0.175006)
			(stroke
				(width 0.1)
				(type default)
			)
			(layer "F.Fab")
		)
		(pad "1" smd rect
			(at -0.2667 0 90)
			(size 0.3048 0.381)
			(layers "F.Cu" "F.Mask" "F.Paste")
			(net "CLK_100M_RETIMER_CPU1_P1_DP")
		)
		(pad "2" smd rect
			(at 0.2667 0 270)
			(size 0.3048 0.381)
			(layers "F.Cu" "F.Mask" "F.Paste")
			(net "GND")
		)
	)
	(footprint ""
		(layer "F.Cu")
		(at 136.962388 -384.10388 180)
		(property "Reference" "R893"
			(at 0 0 180)
			(layer "F.SilkS")
			(hide yes)
			(effects
				(font
					(size 1.27 1.27)
				)
			)
		)
		(property "Value" ""
			(at 0 0 180)
			(layer "F.Fab")
			(effects
				(font
					(size 1.27 1.27)
				)
			)
		)
		(duplicate_pad_numbers_are_jumpers no)
		(fp_line
			(start 0.7874 0.4064)
			(end -0.7874 0.4064)
			(stroke
				(width 0.1524)
				(type default)
			)
			(layer "F.SilkS")
		)
		(fp_line
			(start 0.7874 -0.4064)
			(end 0.7874 0.4064)
			(stroke
				(width 0.1524)
				(type default)
			)
			(layer "F.SilkS")
		)
		(fp_line
			(start -0.7874 0.4064)
			(end -0.7874 -0.4064)
			(stroke
				(width 0.1524)
				(type default)
			)
			(layer "F.SilkS")
		)
		(fp_line
			(start -0.7874 -0.4064)
			(end 0.7874 -0.4064)
			(stroke
				(width 0.1524)
				(type default)
			)
			(layer "F.SilkS")
		)
		(fp_line
			(start 0.67945 0.3048)
			(end 0.120396 0.3048)
			(stroke
				(width 0.1)
				(type default)
			)
			(layer "F.Fab")
		)
		(fp_line
			(start 0.67945 -0.3048)
			(end 0.67945 0.3048)
			(stroke
				(width 0.1)
				(type default)
			)
			(layer "F.Fab")
		)
		(fp_line
			(start 0.12065 -0.2794)
			(end 0.12065 -0.3048)
			(stroke
				(width 0.1)
				(type default)
			)
			(layer "F.Fab")
		)
		(fp_line
			(start 0.12065 -0.3048)
			(end 0.67945 -0.3048)
			(stroke
				(width 0.1)
				(type default)
			)
			(layer "F.Fab")
		)
		(fp_line
			(start 0.120396 0.3048)
			(end 0.120396 0.2794)
			(stroke
				(width 0.1)
				(type default)
			)
			(layer "F.Fab")
		)
		(fp_line
			(start 0.120396 0.2794)
			(end -0.12065 0.2794)
			(stroke
				(width 0.1)
				(type default)
			)
			(layer "F.Fab")
		)
		(fp_line
			(start -0.12065 0.3048)
			(end -0.67945 0.3048)
			(stroke
				(width 0.1)
				(type default)
			)
			(layer "F.Fab")
		)
		(fp_line
			(start -0.12065 0.2794)
			(end -0.12065 0.3048)
			(stroke
				(width 0.1)
				(type default)
			)
			(layer "F.Fab")
		)
		(fp_line
			(start -0.12065 -0.2794)
			(end 0.12065 -0.2794)
			(stroke
				(width 0.1)
				(type default)
			)
			(layer "F.Fab")
		)
		(fp_line
			(start -0.12065 -0.305054)
			(end -0.12065 -0.2794)
			(stroke
				(width 0.1)
				(type default)
			)
			(layer "F.Fab")
		)
		(fp_line
			(start -0.67945 0.3048)
			(end -0.67945 -0.305054)
			(stroke
				(width 0.1)
				(type default)
			)
			(layer "F.Fab")
		)
		(fp_line
			(start -0.67945 -0.305054)
			(end -0.12065 -0.305054)
			(stroke
				(width 0.1)
				(type default)
			)
			(layer "F.Fab")
		)
		(pad "1" smd rect
			(at -0.40005 0)
			(size 0.4572 0.508)
			(layers "F.Cu" "F.Mask" "F.Paste")
			(net "P1V8_CPU1_RT3_1A_1D")
		)
		(pad "2" smd rect
			(at 0.40005 0)
			(size 0.4572 0.508)
			(layers "F.Cu" "F.Mask" "F.Paste")
			(net "P1V8_CPU1_RT3_1A")
		)
	)
	(footprint ""
		(layer "F.Cu")
		(at 254.592836 -116.12245)
		(property "Reference" "R3727"
			(at 0 0 0)
			(layer "F.SilkS")
			(hide yes)
			(effects
				(font
					(size 1.27 1.27)
				)
			)
		)
		(property "Value" ""
			(at 0 0 0)
			(layer "F.Fab")
			(effects
				(font
					(size 1.27 1.27)
				)
			)
		)
		(duplicate_pad_numbers_are_jumpers no)
		(fp_line
			(start -0.7874 -0.4064)
			(end 0.7874 -0.4064)
			(stroke
				(width 0.1524)
				(type default)
			)
			(layer "F.SilkS")
		)
		(fp_line
			(start -0.7874 0.4064)
			(end -0.7874 -0.4064)
			(stroke
				(width 0.1524)
				(type default)
			)
			(layer "F.SilkS")
		)
		(fp_line
			(start 0.7874 -0.4064)
			(end 0.7874 0.4064)
			(stroke
				(width 0.1524)
				(type default)
			)
			(layer "F.SilkS")
		)
		(fp_line
			(start 0.7874 0.4064)
			(end -0.7874 0.4064)
			(stroke
				(width 0.1524)
				(type default)
			)
			(layer "F.SilkS")
		)
		(fp_line
			(start -0.67945 -0.305054)
			(end -0.12065 -0.305054)
			(stroke
				(width 0.1)
				(type default)
			)
			(layer "F.Fab")
		)
		(fp_line
			(start -0.67945 0.3048)
			(end -0.67945 -0.305054)
			(stroke
				(width 0.1)
				(type default)
			)
			(layer "F.Fab")
		)
		(fp_line
			(start -0.12065 -0.305054)
			(end -0.12065 -0.2794)
			(stroke
				(width 0.1)
				(type default)
			)
			(layer "F.Fab")
		)
		(fp_line
			(start -0.12065 -0.2794)
			(end 0.12065 -0.2794)
			(stroke
				(width 0.1)
				(type default)
			)
			(layer "F.Fab")
		)
		(fp_line
			(start -0.12065 0.2794)
			(end -0.12065 0.3048)
			(stroke
				(width 0.1)
				(type default)
			)
			(layer "F.Fab")
		)
		(fp_line
			(start -0.12065 0.3048)
			(end -0.67945 0.3048)
			(stroke
				(width 0.1)
				(type default)
			)
			(layer "F.Fab")
		)
		(fp_line
			(start 0.120396 0.2794)
			(end -0.12065 0.2794)
			(stroke
				(width 0.1)
				(type default)
			)
			(layer "F.Fab")
		)
		(fp_line
			(start 0.120396 0.3048)
			(end 0.120396 0.2794)
			(stroke
				(width 0.1)
				(type default)
			)
			(layer "F.Fab")
		)
		(fp_line
			(start 0.12065 -0.3048)
			(end 0.67945 -0.3048)
			(stroke
				(width 0.1)
				(type default)
			)
			(layer "F.Fab")
		)
		(fp_line
			(start 0.12065 -0.2794)
			(end 0.12065 -0.3048)
			(stroke
				(width 0.1)
				(type default)
			)
			(layer "F.Fab")
		)
		(fp_line
			(start 0.67945 -0.3048)
			(end 0.67945 0.3048)
			(stroke
				(width 0.1)
				(type default)
			)
			(layer "F.Fab")
		)
		(fp_line
			(start 0.67945 0.3048)
			(end 0.120396 0.3048)
			(stroke
				(width 0.1)
				(type default)
			)
			(layer "F.Fab")
		)
		(pad "1" smd circle
			(at -0.40005 0)
			(size 0 0)
			(layers "F.Cu" "F.Mask" "F.Paste")
			(net "P3V3_AUX")
		)
		(pad "2" smd circle
			(at 0.40005 0)
			(size 0 0)
			(layers "F.Cu" "F.Mask" "F.Paste")
			(net "SMB_LM75_1_3V3AUX_SCL")
		)
	)
	(footprint ""
		(layer "F.Cu")
		(at 246.22506 -53.997606 90)
		(property "Reference" "PC2219"
			(at 0 0 90)
			(layer "F.SilkS")
			(hide yes)
			(effects
				(font
					(size 1.27 1.27)
				)
			)
		)
		(property "Value" ""
			(at 0 0 90)
			(layer "F.Fab")
			(effects
				(font
					(size 1.27 1.27)
				)
			)
		)
		(duplicate_pad_numbers_are_jumpers no)
		(fp_line
			(start 1.524 -0.762)
			(end 1.524 0.762)
			(stroke
				(width 0.1524)
				(type default)
			)
			(layer "F.SilkS")
		)
		(fp_line
			(start -1.524 -0.762)
			(end 1.524 -0.762)
			(stroke
				(width 0.1524)
				(type default)
			)
			(layer "F.SilkS")
		)
		(fp_line
			(start 1.524 0.762)
			(end -1.524 0.762)
			(stroke
				(width 0.1524)
				(type default)
			)
			(layer "F.SilkS")
		)
		(fp_line
			(start -1.524 0.762)
			(end -1.524 -0.762)
			(stroke
				(width 0.1524)
				(type default)
			)
			(layer "F.SilkS")
		)
		(fp_line
			(start 1.1049 -0.724916)
			(end -1.1049 -0.724916)
			(stroke
				(width 0.1)
				(type default)
			)
			(layer "F.Fab")
		)
		(fp_line
			(start -1.1049 -0.724916)
			(end -1.1049 0.724916)
			(stroke
				(width 0.1)
				(type default)
			)
			(layer "F.Fab")
		)
		(fp_line
			(start 1.1049 0.724916)
			(end 1.1049 -0.724916)
			(stroke
				(width 0.1)
				(type default)
			)
			(layer "F.Fab")
		)
		(fp_line
			(start -1.1049 0.724916)
			(end 1.1049 0.724916)
			(stroke
				(width 0.1)
				(type default)
			)
			(layer "F.Fab")
		)
		(pad "1" smd rect
			(at -0.889 0 270)
			(size 1.016 1.27)
			(layers "F.Cu" "F.Mask" "F.Paste")
			(net "P12V_E1S_0")
		)
		(pad "2" smd rect
			(at 0.889 0 270)
			(size 1.016 1.27)
			(layers "F.Cu" "F.Mask" "F.Paste")
			(net "GND")
		)
	)
	(footprint ""
		(layer "F.Cu")
		(at 400.22272 -330.575666 90)
		(property "Reference" "R459"
			(at 0 0 90)
			(layer "F.SilkS")
			(hide yes)
			(effects
				(font
					(size 1.27 1.27)
				)
			)
		)
		(property "Value" ""
			(at 0 0 90)
			(layer "F.Fab")
			(effects
				(font
					(size 1.27 1.27)
				)
			)
		)
		(duplicate_pad_numbers_are_jumpers no)
		(fp_line
			(start 0.7874 -0.4064)
			(end 0.7874 0.4064)
			(stroke
				(width 0.1524)
				(type default)
			)
			(layer "F.SilkS")
		)
		(fp_line
			(start -0.7874 -0.4064)
			(end 0.7874 -0.4064)
			(stroke
				(width 0.1524)
				(type default)
			)
			(layer "F.SilkS")
		)
		(fp_line
			(start 0.7874 0.4064)
			(end -0.7874 0.4064)
			(stroke
				(width 0.1524)
				(type default)
			)
			(layer "F.SilkS")
		)
		(fp_line
			(start -0.7874 0.4064)
			(end -0.7874 -0.4064)
			(stroke
				(width 0.1524)
				(type default)
			)
			(layer "F.SilkS")
		)
		(fp_line
			(start -0.12065 -0.305054)
			(end -0.12065 -0.2794)
			(stroke
				(width 0.1)
				(type default)
			)
			(layer "F.Fab")
		)
		(fp_line
			(start -0.67945 -0.305054)
			(end -0.12065 -0.305054)
			(stroke
				(width 0.1)
				(type default)
			)
			(layer "F.Fab")
		)
		(fp_line
			(start 0.67945 -0.3048)
			(end 0.67945 0.3048)
			(stroke
				(width 0.1)
				(type default)
			)
			(layer "F.Fab")
		)
		(fp_line
			(start 0.12065 -0.3048)
			(end 0.67945 -0.3048)
			(stroke
				(width 0.1)
				(type default)
			)
			(layer "F.Fab")
		)
		(fp_line
			(start 0.12065 -0.2794)
			(end 0.12065 -0.3048)
			(stroke
				(width 0.1)
				(type default)
			)
			(layer "F.Fab")
		)
		(fp_line
			(start -0.12065 -0.2794)
			(end 0.12065 -0.2794)
			(stroke
				(width 0.1)
				(type default)
			)
			(layer "F.Fab")
		)
		(fp_line
			(start 0.120396 0.2794)
			(end -0.12065 0.2794)
			(stroke
				(width 0.1)
				(type default)
			)
			(layer "F.Fab")
		)
		(fp_line
			(start -0.12065 0.2794)
			(end -0.12065 0.3048)
			(stroke
				(width 0.1)
				(type default)
			)
			(layer "F.Fab")
		)
		(fp_line
			(start 0.67945 0.3048)
			(end 0.120396 0.3048)
			(stroke
				(width 0.1)
				(type default)
			)
			(layer "F.Fab")
		)
		(fp_line
			(start 0.120396 0.3048)
			(end 0.120396 0.2794)
			(stroke
				(width 0.1)
				(type default)
			)
			(layer "F.Fab")
		)
		(fp_line
			(start -0.12065 0.3048)
			(end -0.67945 0.3048)
			(stroke
				(width 0.1)
				(type default)
			)
			(layer "F.Fab")
		)
		(fp_line
			(start -0.67945 0.3048)
			(end -0.67945 -0.305054)
			(stroke
				(width 0.1)
				(type default)
			)
			(layer "F.Fab")
		)
		(pad "1" smd circle
			(at -0.40005 0 90)
			(size 0 0)
			(layers "F.Cu" "F.Mask" "F.Paste")
			(net "SPI_CPU0_CS0_N")
		)
		(pad "2" smd circle
			(at 0.40005 0 90)
			(size 0 0)
			(layers "F.Cu" "F.Mask" "F.Paste")
			(net "SPI_CPU0_R_CS0_N")
		)
	)
	(footprint ""
		(layer "F.Cu")
		(at 327.179178 -41.160954)
		(property "Reference" "R1785"
			(at 0 0 0)
			(layer "F.SilkS")
			(hide yes)
			(effects
				(font
					(size 1.27 1.27)
				)
			)
		)
		(property "Value" ""
			(at 0 0 0)
			(layer "F.Fab")
			(effects
				(font
					(size 1.27 1.27)
				)
			)
		)
		(duplicate_pad_numbers_are_jumpers no)
		(fp_line
			(start -0.7874 -0.4064)
			(end 0.7874 -0.4064)
			(stroke
				(width 0.1524)
				(type default)
			)
			(layer "F.SilkS")
		)
		(fp_line
			(start -0.7874 0.4064)
			(end -0.7874 -0.4064)
			(stroke
				(width 0.1524)
				(type default)
			)
			(layer "F.SilkS")
		)
		(fp_line
			(start 0.7874 -0.4064)
			(end 0.7874 0.4064)
			(stroke
				(width 0.1524)
				(type default)
			)
			(layer "F.SilkS")
		)
		(fp_line
			(start 0.7874 0.4064)
			(end -0.7874 0.4064)
			(stroke
				(width 0.1524)
				(type default)
			)
			(layer "F.SilkS")
		)
		(fp_line
			(start -0.67945 -0.305054)
			(end -0.12065 -0.305054)
			(stroke
				(width 0.1)
				(type default)
			)
			(layer "F.Fab")
		)
		(fp_line
			(start -0.67945 0.3048)
			(end -0.67945 -0.305054)
			(stroke
				(width 0.1)
				(type default)
			)
			(layer "F.Fab")
		)
		(fp_line
			(start -0.12065 -0.305054)
			(end -0.12065 -0.2794)
			(stroke
				(width 0.1)
				(type default)
			)
			(layer "F.Fab")
		)
		(fp_line
			(start -0.12065 -0.2794)
			(end 0.12065 -0.2794)
			(stroke
				(width 0.1)
				(type default)
			)
			(layer "F.Fab")
		)
		(fp_line
			(start -0.12065 0.2794)
			(end -0.12065 0.3048)
			(stroke
				(width 0.1)
				(type default)
			)
			(layer "F.Fab")
		)
		(fp_line
			(start -0.12065 0.3048)
			(end -0.67945 0.3048)
			(stroke
				(width 0.1)
				(type default)
			)
			(layer "F.Fab")
		)
		(fp_line
			(start 0.120396 0.2794)
			(end -0.12065 0.2794)
			(stroke
				(width 0.1)
				(type default)
			)
			(layer "F.Fab")
		)
		(fp_line
			(start 0.120396 0.3048)
			(end 0.120396 0.2794)
			(stroke
				(width 0.1)
				(type default)
			)
			(layer "F.Fab")
		)
		(fp_line
			(start 0.12065 -0.3048)
			(end 0.67945 -0.3048)
			(stroke
				(width 0.1)
				(type default)
			)
			(layer "F.Fab")
		)
		(fp_line
			(start 0.12065 -0.2794)
			(end 0.12065 -0.3048)
			(stroke
				(width 0.1)
				(type default)
			)
			(layer "F.Fab")
		)
		(fp_line
			(start 0.67945 -0.3048)
			(end 0.67945 0.3048)
			(stroke
				(width 0.1)
				(type default)
			)
			(layer "F.Fab")
		)
		(fp_line
			(start 0.67945 0.3048)
			(end 0.120396 0.3048)
			(stroke
				(width 0.1)
				(type default)
			)
			(layer "F.Fab")
		)
		(pad "1" smd circle
			(at -0.40005 0)
			(size 0 0)
			(layers "F.Cu" "F.Mask" "F.Paste")
			(net "P3V3_AUX_ADC")
		)
		(pad "2" smd circle
			(at 0.40005 0)
			(size 0 0)
			(layers "F.Cu" "F.Mask" "F.Paste")
			(net "GND")
		)
	)
)
